# T6G (Grand Teton) — schematic netlist excerpt (pin names and nets, part order shuffled) for the footprints in the layout excerpt that follows; sources: Cadence DE-HDL packaged netlist, KiCad conversion of 04192023_DAF0TMB3IC0_F0TG_MB_C_brd_V02_OCP.brd

J71  PICOPROBE_BXA  DELTA-L 4.0 EMPTY  pkg TRIANG_LAUNCH_3PXB  page 229
  \1_p\  = DELTA_L_85_5INCH_IN1_DN
  \2_n\  = DELTA_L_85_5INCH_IN1_DP
  \3_g\  = DELTA_L_GND_1

(kicad_pcb
	(version 20260206)
	(generator "pcbnew")
	(generator_version "10.0")
	(general
		(thickness 1.6)
		(legacy_teardrops no)
	)
	(paper "A4")
	(title_block
		(title "04192023_DAF0TMB3IC0_F0TG_MB_C_brd_V02_OCP.brd")
		(comment 1 "Grand Teton / footprints 1461-1461 of 8354")
	)
	(layers
		(0 "F.Cu" signal "TOP")
		(4 "In1.Cu" signal "GND")
		(6 "In2.Cu" signal "IN1")
		(8 "In3.Cu" signal "GND1")
		(10 "In4.Cu" signal "IN2")
		(12 "In5.Cu" signal "GND2")
		(14 "In6.Cu" signal "IN3")
		(16 "In7.Cu" signal "GND3")
		(18 "In8.Cu" signal "VCC")
		(20 "In9.Cu" signal "VCC1")
		(22 "In10.Cu" signal "GND4")
		(24 "In11.Cu" signal "IN4")
		(26 "In12.Cu" signal "GND5")
		(28 "In13.Cu" signal "IN5")
		(30 "In14.Cu" signal "GND6")
		(32 "In15.Cu" signal "IN6")
		(34 "In16.Cu" signal "GND7")
		(2 "B.Cu" signal "BOTTOM")
		(9 "F.Adhes" user "F.Adhesive")
		(11 "B.Adhes" user "B.Adhesive")
		(13 "F.Paste" user "Package Geometry/Pastemask Top")
		(15 "B.Paste" user "Package Geometry/Pastemask Bottom")
		(5 "F.SilkS" user "Ref Des/Silkscreen Top")
		(7 "B.SilkS" user "Ref Des/Silkscreen Bottom")
		(1 "F.Mask" user "Board Geometry/Soldermask Top")
		(3 "B.Mask" user "Board Geometry/Soldermask Bottom")
		(17 "Dwgs.User" user "User.Drawings")
		(19 "Cmts.User" user "User.Comments")
		(21 "Eco1.User" user "User.Eco1")
		(23 "Eco2.User" user "User.Eco2")
		(25 "Edge.Cuts" user "Board Geometry/Outline")
		(27 "Margin" user)
		(31 "F.CrtYd" user "Package Geometry/Place Bound Top")
		(29 "B.CrtYd" user "Package Geometry/Place Bound Bottom")
		(35 "F.Fab" user "Ref Des/Assembly Top")
		(33 "B.Fab" user "Ref Des/Assembly Bottom")
	)
	(footprint ""
		(layer "F.Cu")
		(at 314.965588 5.082794)
		(property "Reference" "J71"
			(at -4.421886 0.954786 90)
			(unlocked yes)
			(layer "F.SilkS")
			(effects
				(font
					(size 0.7874 0.5842)
					(thickness 0.1524)
				)
				(justify left)
			)
		)
		(property "Value" ""
			(at 0 0 0)
			(layer "F.Fab")
			(effects
				(font
					(size 1.27 1.27)
				)
			)
		)
		(duplicate_pad_numbers_are_jumpers no)
		(fp_line
			(start -1.2192 -2.06756)
			(end 1.2192 -2.06756)
			(stroke
				(width 0.1524)
				(type default)
			)
			(layer "F.SilkS")
		)
		(fp_line
			(start -1.2192 2.06756)
			(end -1.2192 -2.06756)
			(stroke
				(width 0.1524)
				(type default)
			)
			(layer "F.SilkS")
		)
		(fp_line
			(start 1.2192 -2.06756)
			(end 1.2192 2.06756)
			(stroke
				(width 0.1524)
				(type default)
			)
			(layer "F.SilkS")
		)
		(fp_line
			(start 1.2192 2.06756)
			(end -1.2192 2.06756)
			(stroke
				(width 0.1524)
				(type default)
			)
			(layer "F.SilkS")
		)
		(pad "" np_thru_hole circle
			(at -2.8829 -1.27 270)
			(size 1.0414 1.0414)
			(drill 1.0414)
			(layers "*.Cu" "*.Mask")
			(clearance 0.381)
			(thermal_gap 0.381)
		)
		(pad "" np_thru_hole circle
			(at -2.8829 1.27 270)
			(size 1.0414 1.0414)
			(drill 1.0414)
			(layers "*.Cu" "*.Mask")
			(clearance 0.381)
			(thermal_gap 0.381)
		)
		(pad "" np_thru_hole circle
			(at 3.4671 -1.27 270)
			(size 1.0414 1.0414)
			(drill 1.0414)
			(layers "*.Cu" "*.Mask")
			(clearance 0.381)
			(thermal_gap 0.381)
		)
		(pad "" np_thru_hole circle
			(at 3.4671 1.27 270)
			(size 1.0414 1.0414)
			(drill 1.0414)
			(layers "*.Cu" "*.Mask")
			(clearance 0.381)
			(thermal_gap 0.381)
		)
		(pad "1" smd rect
			(at 0.8255 -0.249936 270)
			(size 0.3048 0.508)
			(layers "F.Cu" "F.Mask" "F.Paste")
			(net "DELTA_L_85_5INCH_IN1_DN")
		)
		(pad "2" smd rect
			(at 0.8255 0.249936 270)
			(size 0.3048 0.508)
			(layers "F.Cu" "F.Mask" "F.Paste")
			(net "DELTA_L_85_5INCH_IN1_DP")
		)
		(pad "3" smd circle
			(at 0 0)
			(size 0 0)
			(layers "F.Cu" "F.Mask" "F.Paste")
			(net "DELTA_L_GND_1")
		)
		(zone
			(layer "F.Cu")
			(hatch none 0.5)
			(connect_pads
				(clearance 0)
			)
			(min_thickness 0.25)
			(keepout
				(tracks not_allowed)
				(vias allowed)
				(pads allowed)
				(copperpour not_allowed)
				(footprints allowed)
			)
			(placement
				(enabled no)
				(sheetname "")
			)
			(fill
				(thermal_gap 0.5)
				(thermal_bridge_width 0.5)
				(island_removal_mode 0)
			)
			(polygon
				(pts
					(xy 316.083188 4.534154) (xy 316.083188 4.629658) (xy 315.486288 4.629658) (xy 315.486288 5.036058)
					(xy 316.083188 5.036058) (xy 316.083188 5.12953) (xy 315.486288 5.12953) (xy 315.486288 5.53593)
					(xy 316.083188 5.53593) (xy 316.083188 5.631434) (xy 315.384688 5.631434) (xy 315.384688 4.534154)
				)
			)
		)
		(zone
			(layers "F.Cu" "B.Cu" "In1.Cu" "In2.Cu" "In3.Cu" "In4.Cu" "In5.Cu" "In6.Cu"
				"In7.Cu" "In8.Cu" "In9.Cu" "In10.Cu" "In11.Cu" "In12.Cu" "In13.Cu" "In14.Cu"
				"In15.Cu" "In16.Cu"
			)
			(hatch none 0.5)
			(connect_pads
				(clearance 0)
			)
			(min_thickness 0.25)
			(keepout
				(tracks not_allowed)
				(vias allowed)
				(pads allowed)
				(copperpour not_allowed)
				(footprints allowed)
			)
			(placement
				(enabled no)
				(sheetname "")
			)
			(fill
				(thermal_gap 0.5)
				(thermal_bridge_width 0.5)
				(island_removal_mode 0)
			)
			(polygon
				(pts
					(arc
						(start 313.009788 3.812794)
						(mid 311.155588 3.812794)
						(end 313.009788 3.812794)
					)
				)
			)
		)
		(zone
			(layers "F.Cu" "B.Cu" "In1.Cu" "In2.Cu" "In3.Cu" "In4.Cu" "In5.Cu" "In6.Cu"
				"In7.Cu" "In8.Cu" "In9.Cu" "In10.Cu" "In11.Cu" "In12.Cu" "In13.Cu" "In14.Cu"
				"In15.Cu" "In16.Cu"
			)
			(hatch none 0.5)
			(connect_pads
				(clearance 0)
			)
			(min_thickness 0.25)
			(keepout
				(tracks not_allowed)
				(vias allowed)
				(pads allowed)
				(copperpour not_allowed)
				(footprints allowed)
			)
			(placement
				(enabled no)
				(sheetname "")
			)
			(fill
				(thermal_gap 0.5)
				(thermal_bridge_width 0.5)
				(island_removal_mode 0)
			)
			(polygon
				(pts
					(arc
						(start 313.009788 6.352794)
						(mid 311.155588 6.352794)
						(end 313.009788 6.352794)
					)
				)
			)
		)
		(zone
			(layers "F.Cu" "B.Cu" "In1.Cu" "In2.Cu" "In3.Cu" "In4.Cu" "In5.Cu" "In6.Cu"
				"In7.Cu" "In8.Cu" "In9.Cu" "In10.Cu" "In11.Cu" "In12.Cu" "In13.Cu" "In14.Cu"
				"In15.Cu" "In16.Cu"
			)
			(hatch none 0.5)
			(connect_pads
				(clearance 0)
			)
			(min_thickness 0.25)
			(keepout
				(tracks not_allowed)
				(vias allowed)
				(pads allowed)
				(copperpour not_allowed)
				(footprints allowed)
			)
			(placement
				(enabled no)
				(sheetname "")
			)
			(fill
				(thermal_gap 0.5)
				(thermal_bridge_width 0.5)
				(island_removal_mode 0)
			)
			(polygon
				(pts
					(arc
						(start 319.359788 3.812794)
						(mid 317.505588 3.812794)
						(end 319.359788 3.812794)
					)
				)
			)
		)
		(zone
			(layers "F.Cu" "B.Cu" "In1.Cu" "In2.Cu" "In3.Cu" "In4.Cu" "In5.Cu" "In6.Cu"
				"In7.Cu" "In8.Cu" "In9.Cu" "In10.Cu" "In11.Cu" "In12.Cu" "In13.Cu" "In14.Cu"
				"In15.Cu" "In16.Cu"
			)
			(hatch none 0.5)
			(connect_pads
				(clearance 0)
			)
			(min_thickness 0.25)
			(keepout
				(tracks not_allowed)
				(vias allowed)
				(pads allowed)
				(copperpour not_allowed)
				(footprints allowed)
			)
			(placement
				(enabled no)
				(sheetname "")
			)
			(fill
				(thermal_gap 0.5)
				(thermal_bridge_width 0.5)
				(island_removal_mode 0)
			)
			(polygon
				(pts
					(arc
						(start 319.359788 6.352794)
						(mid 317.505588 6.352794)
						(end 319.359788 6.352794)
					)
				)
			)
		)
	)
)
